(kicad_pcb
	(version 20260206)
	(generator "pcbnew")
	(generator_version "10.0")
	(general
		(thickness 1.6)
		(legacy_teardrops no)
	)
	(paper "A4")
	(title_block
		(title "v1-chassis-manager — T6M_CM_d_v01_1031_1645.brd")
		(comment 1 "Open CloudServer (Microsoft) / footprints 167-174 of 2512")
	)
	(layers
		(0 "F.Cu" signal "TOP")
		(4 "In1.Cu" signal "GND1")
		(6 "In2.Cu" signal "IN1")
		(8 "In3.Cu" signal "VCC1")
		(10 "In4.Cu" signal "VCC2")
		(12 "In5.Cu" signal "GND2")
		(14 "In6.Cu" signal "IN2")
		(16 "In7.Cu" signal "IN3")
		(18 "In8.Cu" signal "GND3")
		(2 "B.Cu" signal "BOTTOM")
		(9 "F.Adhes" user "F.Adhesive")
		(11 "B.Adhes" user "B.Adhesive")
		(13 "F.Paste" user "Package Geometry/Pastemask Top")
		(15 "B.Paste" user "Package Geometry/Pastemask Bottom")
		(5 "F.SilkS" user "Ref Des/Silkscreen Top")
		(7 "B.SilkS" user "Ref Des/Silkscreen Bottom")
		(1 "F.Mask" user "Board Geometry/Soldermask Top")
		(3 "B.Mask" user "Board Geometry/Soldermask Bottom")
		(17 "Dwgs.User" user "User.Drawings")
		(19 "Cmts.User" user "User.Comments")
		(21 "Eco1.User" user "User.Eco1")
		(23 "Eco2.User" user "User.Eco2")
		(25 "Edge.Cuts" user "Board Geometry/Outline")
		(27 "Margin" user)
		(31 "F.CrtYd" user "Package Geometry/Place Bound Top")
		(29 "B.CrtYd" user "Package Geometry/Place Bound Bottom")
		(35 "F.Fab" user "Ref Des/Assembly Top")
		(33 "B.Fab" user "Ref Des/Assembly Bottom")
	)
	(footprint ""
		(layer "F.Cu")
		(at 60.05957 -110.27029 180)
		(property "Reference" "PC16"
			(at 1.977644 -6.787134 0)
			(unlocked yes)
			(layer "F.SilkS")
			(effects
				(font
					(size 0.7874 0.5842)
					(thickness 0.1524)
				)
				(justify left)
			)
		)
		(property "Value" ""
			(at 0 0 180)
			(layer "F.Fab")
			(effects
				(font
					(size 1.27 1.27)
				)
			)
		)
		(duplicate_pad_numbers_are_jumpers no)
		(fp_line
			(start 1.905 0.8636)
			(end -1.905 0.8636)
			(stroke
				(width 0.1524)
				(type default)
			)
			(layer "F.SilkS")
		)
		(fp_line
			(start 1.905 -0.8636)
			(end 1.905 0.8636)
			(stroke
				(width 0.1524)
				(type default)
			)
			(layer "F.SilkS")
		)
		(fp_line
			(start 0 0.8382)
			(end 0 -0.8382)
			(stroke
				(width 0.1524)
				(type default)
			)
			(layer "F.SilkS")
		)
		(fp_line
			(start -1.905 0.8636)
			(end -1.905 -0.8636)
			(stroke
				(width 0.1524)
				(type default)
			)
			(layer "F.SilkS")
		)
		(fp_line
			(start -1.905 -0.8636)
			(end 1.905 -0.8636)
			(stroke
				(width 0.1524)
				(type default)
			)
			(layer "F.SilkS")
		)
		(fp_rect
			(start -1.524 0.7366)
			(end 1.524 -0.7366)
			(stroke
				(width 0)
				(type default)
			)
			(fill no)
			(layer "F.CrtYd")
		)
		(pad "1" smd rect
			(at 0.94996 0 180)
			(size 1.1176 1.3716)
			(layers "F.Cu" "F.Mask" "F.Paste")
			(net "P3V3_STB_NODE1")
		)
		(pad "2" smd rect
			(at -0.94996 0 180)
			(size 1.1176 1.3716)
			(layers "F.Cu" "F.Mask" "F.Paste")
			(net "GND")
		)
	)
	(footprint ""
		(layer "F.Cu")
		(at 47.10176 -182.246524 90)
		(property "Reference" "C614"
			(at -133.313932 -3.637788 90)
			(unlocked yes)
			(layer "F.SilkS")
			(effects
				(font
					(size 0.7874 0.5842)
					(thickness 0.1524)
				)
				(justify left)
			)
		)
		(property "Value" ""
			(at 0 0 90)
			(layer "F.Fab")
			(effects
				(font
					(size 1.27 1.27)
				)
			)
		)
		(duplicate_pad_numbers_are_jumpers no)
		(fp_line
			(start 0.7874 -0.4064)
			(end 0.7874 0.4064)
			(stroke
				(width 0.1524)
				(type default)
			)
			(layer "F.SilkS")
		)
		(fp_line
			(start -0.7874 -0.4064)
			(end 0.7874 -0.4064)
			(stroke
				(width 0.1524)
				(type default)
			)
			(layer "F.SilkS")
		)
		(fp_line
			(start 0 0.381)
			(end 0 -0.381)
			(stroke
				(width 0.1524)
				(type default)
			)
			(layer "F.SilkS")
		)
		(fp_line
			(start 0.7874 0.4064)
			(end -0.7874 0.4064)
			(stroke
				(width 0.1524)
				(type default)
			)
			(layer "F.SilkS")
		)
		(fp_line
			(start -0.7874 0.4064)
			(end -0.7874 -0.4064)
			(stroke
				(width 0.1524)
				(type default)
			)
			(layer "F.SilkS")
		)
		(fp_poly
			(pts
				(xy -0.5334 0.254) (xy -0.635 0.254) (xy -0.635 0.2286) (xy -0.635 -0.254) (xy -0.5334 -0.254) (xy -0.5334 -0.2794)
				(xy 0.5334 -0.2794) (xy 0.5334 -0.254) (xy 0.635 -0.254) (xy 0.635 0.254) (xy 0.5334 0.254) (xy 0.5334 0.2794)
				(xy -0.508 0.2794) (xy -0.5334 0.2794)
			)
			(stroke
				(width 0)
				(type default)
			)
			(fill no)
			(layer "F.CrtYd")
		)
		(pad "1" smd rect
			(at 0.40005 0 90)
			(size 0.4572 0.508)
			(layers "F.Cu" "F.Mask" "F.Paste")
			(net "PSU6_AC_OK")
		)
		(pad "2" smd rect
			(at -0.40005 0 90)
			(size 0.4572 0.508)
			(layers "F.Cu" "F.Mask" "F.Paste")
			(net "GND")
		)
	)
	(footprint ""
		(layer "F.Cu")
		(at 83.245706 -129.052574 -90)
		(property "Reference" "R1260"
			(at 5.993892 4.44754 90)
			(unlocked yes)
			(layer "F.SilkS")
			(effects
				(font
					(size 0.7874 0.5842)
					(thickness 0.1524)
				)
				(justify left)
			)
		)
		(property "Value" ""
			(at 0 0 270)
			(layer "F.Fab")
			(effects
				(font
					(size 1.27 1.27)
				)
			)
		)
		(duplicate_pad_numbers_are_jumpers no)
		(fp_line
			(start -0.7874 0.4064)
			(end -0.7874 -0.4064)
			(stroke
				(width 0.1524)
				(type default)
			)
			(layer "F.SilkS")
		)
		(fp_line
			(start 0.7874 0.4064)
			(end -0.7874 0.4064)
			(stroke
				(width 0.1524)
				(type default)
			)
			(layer "F.SilkS")
		)
		(fp_line
			(start -0.7874 -0.4064)
			(end 0.7874 -0.4064)
			(stroke
				(width 0.1524)
				(type default)
			)
			(layer "F.SilkS")
		)
		(fp_line
			(start 0.7874 -0.4064)
			(end 0.7874 0.4064)
			(stroke
				(width 0.1524)
				(type default)
			)
			(layer "F.SilkS")
		)
		(fp_poly
			(pts
				(xy -0.508 0.2794) (xy -0.508 0.2286) (xy -0.635 0.2286) (xy -0.635 -0.254) (xy -0.5334 -0.254)
				(xy -0.5334 -0.2794) (xy 0.5334 -0.2794) (xy 0.5334 -0.254) (xy 0.635 -0.254) (xy 0.635 0.254) (xy 0.5334 0.254)
				(xy 0.5334 0.2794)
			)
			(stroke
				(width 0)
				(type default)
			)
			(fill no)
			(layer "F.CrtYd")
		)
		(pad "1" smd rect
			(at 0.40005 0 270)
			(size 0.4572 0.508)
			(layers "F.Cu" "F.Mask" "F.Paste")
			(net "PORT80_LOUT0")
		)
		(pad "2" smd rect
			(at -0.40005 0 270)
			(size 0.4572 0.508)
			(layers "F.Cu" "F.Mask" "F.Paste")
			(net "N53313646")
		)
	)
	(footprint ""
		(layer "F.Cu")
		(at 69.842888 -2.723642 180)
		(property "Reference" "PJ5"
			(at 2.811018 -2.520442 90)
			(unlocked yes)
			(layer "F.SilkS")
			(effects
				(font
					(size 0.7874 0.5842)
					(thickness 0.1524)
				)
				(justify left)
			)
		)
		(property "Value" ""
			(at 0 0 180)
			(layer "F.Fab")
			(effects
				(font
					(size 1.27 1.27)
				)
			)
		)
		(duplicate_pad_numbers_are_jumpers no)
		(fp_poly
			(pts
				(xy 0.2794 0.907796) (xy 0.254 0.907796) (xy 0.254 1.0414) (xy -0.254 1.0414) (xy -0.254 1.034796)
				(xy -0.254 0.933196) (xy -0.2794 0.933196) (xy -0.2794 -0.133604) (xy -0.254 -0.133604) (xy -0.254 -0.235204)
				(xy 0.254 -0.235204) (xy 0.254 -0.133604) (xy 0.2794 -0.133604)
			)
			(stroke
				(width 0)
				(type default)
			)
			(fill no)
			(layer "F.CrtYd")
		)
		(pad "1" smd custom
			(at 0 -0.000254 180)
			(size 0.127 0.127)
			(layers "F.Cu" "F.Mask" "F.Paste")
			(net "FM_CPLD_NODE1_P3V3_EN")
			(options
				(clearance outline)
				(anchor circle)
			)
			(primitives
				(gr_poly
					(pts
						(xy -0.127 0.508) (xy -0.127 -0.0508) (xy -0.254 -0.0508) (xy -0.254 -0.508) (xy 0.254 -0.508)
						(xy 0.254 -0.0508) (xy 0.127 -0.0508) (xy 0.127 0.508)
					)
					(width 0)
					(fill yes)
				)
			)
		)
		(pad "2" smd rect
			(at 0 0.799846 270)
			(size 0.4572 0.508)
			(layers "F.Cu" "F.Mask" "F.Paste")
			(net "FM_CPLD_NODE1_P3V3_S_EN")
		)
		(zone
			(layer "F.Cu")
			(hatch none 0.5)
			(connect_pads
				(clearance 0)
			)
			(min_thickness 0.25)
			(keepout
				(tracks allowed)
				(vias not_allowed)
				(pads allowed)
				(copperpour not_allowed)
				(footprints allowed)
			)
			(placement
				(enabled no)
				(sheetname "")
			)
			(fill
				(thermal_gap 0.5)
				(thermal_bridge_width 0.5)
				(island_removal_mode 0)
			)
			(polygon
				(pts
					(xy 70.147688 -3.809238) (xy 69.538088 -3.809238) (xy 69.538088 -2.437638) (xy 70.147688 -2.437638)
				)
			)
		)
	)
	(footprint ""
		(layer "F.Cu")
		(at 4.028186 -27.828494 180)
		(property "Reference" "J36"
			(at -0.899414 2.015236 0)
			(unlocked yes)
			(layer "F.SilkS")
			(effects
				(font
					(size 0.7874 0.5842)
					(thickness 0.1524)
				)
				(justify left)
			)
		)
		(property "Value" ""
			(at 0 0 180)
			(layer "F.Fab")
			(effects
				(font
					(size 1.27 1.27)
				)
			)
		)
		(duplicate_pad_numbers_are_jumpers no)
		(fp_line
			(start 2.715006 1.249934)
			(end -2.715006 1.249934)
			(stroke
				(width 0.1524)
				(type default)
			)
			(layer "F.SilkS")
		)
		(fp_line
			(start 2.715006 -1.249934)
			(end 2.715006 1.249934)
			(stroke
				(width 0.1524)
				(type default)
			)
			(layer "F.SilkS")
		)
		(fp_line
			(start 1.27 -1.249934)
			(end 1.27 -7.249922)
			(stroke
				(width 0.635)
				(type default)
			)
			(layer "F.SilkS")
		)
		(fp_line
			(start -1.27 -7.249922)
			(end -1.27 -1.249934)
			(stroke
				(width 0.635)
				(type default)
			)
			(layer "F.SilkS")
		)
		(fp_line
			(start -2.715006 1.249934)
			(end -2.715006 -1.249934)
			(stroke
				(width 0.1524)
				(type default)
			)
			(layer "F.SilkS")
		)
		(fp_line
			(start -2.715006 -1.249934)
			(end 2.715006 -1.249934)
			(stroke
				(width 0.1524)
				(type default)
			)
			(layer "F.SilkS")
		)
		(fp_poly
			(pts
				(xy 1.4224 1.230122) (xy 0.879602 2.652776) (xy 1.890522 2.652776)
			)
			(stroke
				(width 0)
				(type default)
			)
			(fill yes)
			(layer "F.SilkS")
		)
		(fp_poly
			(pts
				(xy 2.0828 -0.8128) (xy 2.0828 0.8128) (xy -2.0828 0.8128) (xy -2.0828 -0.8128)
			)
			(stroke
				(width 0)
				(type default)
			)
			(fill no)
			(layer "B.CrtYd")
		)
		(fp_poly
			(pts
				(xy -2.715006 1.249934) (xy 2.715006 1.249934) (xy 2.715006 -1.249934) (xy 1.6002 -1.249934) (xy 1.6002 -7.5692)
				(xy -1.6002 -7.5692) (xy -1.6002 -1.249934) (xy -2.715006 -1.249934)
			)
			(stroke
				(width 0)
				(type default)
			)
			(fill no)
			(layer "F.CrtYd")
		)
		(fp_line
			(start 2.715006 1.249934)
			(end -2.715006 1.249934)
			(stroke
				(width 0.1)
				(type default)
			)
			(layer "F.Fab")
		)
		(fp_line
			(start 2.715006 -1.249934)
			(end 2.715006 1.249934)
			(stroke
				(width 0.1)
				(type default)
			)
			(layer "F.Fab")
		)
		(fp_line
			(start -2.715006 1.249934)
			(end -2.715006 -1.249934)
			(stroke
				(width 0.1)
				(type default)
			)
			(layer "F.Fab")
		)
		(fp_line
			(start -2.715006 -1.249934)
			(end 2.715006 -1.249934)
			(stroke
				(width 0.1)
				(type default)
			)
			(layer "F.Fab")
		)
		(fp_text user "1"
			(at 3.469386 -0.092964 0)
			(unlocked yes)
			(layer "F.SilkS")
			(effects
				(font
					(size 0.7874 0.5842)
					(thickness 0.1524)
				)
				(justify left)
			)
		)
		(fp_text user "2"
			(at -3.083814 0.059436 0)
			(unlocked yes)
			(layer "F.SilkS")
			(effects
				(font
					(size 0.7874 0.5842)
					(thickness 0.1524)
				)
				(justify left)
			)
		)
		(fp_text user "1"
			(at 2.351786 0.084836 0)
			(unlocked yes)
			(layer "B.SilkS")
			(effects
				(font
					(size 0.7874 0.5842)
					(thickness 0.1524)
				)
				(justify left mirror)
			)
		)
		(fp_text user "2"
			(at -2.804414 0.186436 0)
			(unlocked yes)
			(layer "B.SilkS")
			(effects
				(font
					(size 0.7874 0.5842)
					(thickness 0.1524)
				)
				(justify left mirror)
			)
		)
		(pad "1" thru_hole rect
			(at 1.27 0 180)
			(size 1.524 1.524)
			(drill 1.016)
			(layers "*.Cu" "*.Mask")
			(remove_unused_layers no)
			(net "GND")
			(clearance 0)
			(padstack
				(mode front_inner_back)
				(layer "Inner"
					(shape circle)
					(size 1.524 1.524)
					(clearance 0)
				)
				(layer "B.Cu"
					(shape rect)
					(size 1.524 1.524)
					(clearance 0)
				)
			)
		)
		(pad "2" thru_hole circle
			(at -1.27 0 180)
			(size 1.524 1.524)
			(drill 1.016)
			(layers "*.Cu" "*.Mask")
			(remove_unused_layers no)
			(net "MATE_N")
			(clearance 0)
		)
	)
	(footprint ""
		(layer "F.Cu")
		(at 8.34009 -7.725156)
		(property "Reference" "R213"
			(at -6.44398 -0.688086 0)
			(unlocked yes)
			(layer "F.SilkS")
			(effects
				(font
					(size 0.7874 0.5842)
					(thickness 0.1524)
				)
				(justify left)
			)
		)
		(property "Value" ""
			(at 0 0 0)
			(layer "F.Fab")
			(effects
				(font
					(size 1.27 1.27)
				)
			)
		)
		(duplicate_pad_numbers_are_jumpers no)
		(fp_line
			(start -0.7874 -0.4064)
			(end 0.7874 -0.4064)
			(stroke
				(width 0.1524)
				(type default)
			)
			(layer "F.SilkS")
		)
		(fp_line
			(start -0.7874 0.4064)
			(end -0.7874 -0.4064)
			(stroke
				(width 0.1524)
				(type default)
			)
			(layer "F.SilkS")
		)
		(fp_line
			(start 0.7874 -0.4064)
			(end 0.7874 0.4064)
			(stroke
				(width 0.1524)
				(type default)
			)
			(layer "F.SilkS")
		)
		(fp_line
			(start 0.7874 0.4064)
			(end -0.7874 0.4064)
			(stroke
				(width 0.1524)
				(type default)
			)
			(layer "F.SilkS")
		)
		(fp_poly
			(pts
				(xy -0.508 0.2794) (xy -0.508 0.2286) (xy -0.635 0.2286) (xy -0.635 -0.254) (xy -0.5334 -0.254)
				(xy -0.5334 -0.2794) (xy 0.5334 -0.2794) (xy 0.5334 -0.254) (xy 0.635 -0.254) (xy 0.635 0.254) (xy 0.5334 0.254)
				(xy 0.5334 0.2794)
			)
			(stroke
				(width 0)
				(type default)
			)
			(fill no)
			(layer "F.CrtYd")
		)
		(pad "1" smd rect
			(at 0.40005 0)
			(size 0.4572 0.508)
			(layers "F.Cu" "F.Mask" "F.Paste")
			(net "PV_VDDR_NODE1_VREF_RW")
		)
		(pad "2" smd rect
			(at -0.40005 0)
			(size 0.4572 0.508)
			(layers "F.Cu" "F.Mask" "F.Paste")
			(net "GND")
		)
	)
	(footprint ""
		(layer "F.Cu")
		(at 161.070798 -161.370518 90)
		(property "Reference" "R576"
			(at -8.066278 17.684496 90)
			(unlocked yes)
			(layer "F.SilkS")
			(effects
				(font
					(size 0.7874 0.5842)
					(thickness 0.1524)
				)
				(justify left)
			)
		)
		(property "Value" ""
			(at 0 0 90)
			(layer "F.Fab")
			(effects
				(font
					(size 1.27 1.27)
				)
			)
		)
		(duplicate_pad_numbers_are_jumpers no)
		(fp_line
			(start 0.7874 -0.4064)
			(end 0.7874 0.4064)
			(stroke
				(width 0.1524)
				(type default)
			)
			(layer "F.SilkS")
		)
		(fp_line
			(start -0.7874 -0.4064)
			(end 0.7874 -0.4064)
			(stroke
				(width 0.1524)
				(type default)
			)
			(layer "F.SilkS")
		)
		(fp_line
			(start 0.7874 0.4064)
			(end -0.7874 0.4064)
			(stroke
				(width 0.1524)
				(type default)
			)
			(layer "F.SilkS")
		)
		(fp_line
			(start -0.7874 0.4064)
			(end -0.7874 -0.4064)
			(stroke
				(width 0.1524)
				(type default)
			)
			(layer "F.SilkS")
		)
		(fp_poly
			(pts
				(xy -0.508 0.2794) (xy -0.508 0.2286) (xy -0.635 0.2286) (xy -0.635 -0.254) (xy -0.5334 -0.254)
				(xy -0.5334 -0.2794) (xy 0.5334 -0.2794) (xy 0.5334 -0.254) (xy 0.635 -0.254) (xy 0.635 0.254) (xy 0.5334 0.254)
				(xy 0.5334 0.2794)
			)
			(stroke
				(width 0)
				(type default)
			)
			(fill no)
			(layer "F.CrtYd")
		)
		(pad "1" smd rect
			(at 0.40005 0 90)
			(size 0.4572 0.508)
			(layers "F.Cu" "F.Mask" "F.Paste")
			(net "P3V3_NODE1")
		)
		(pad "2" smd rect
			(at -0.40005 0 90)
			(size 0.4572 0.508)
			(layers "F.Cu" "F.Mask" "F.Paste")
			(net "LAN2_NC_SI_TDX1")
		)
	)
	(footprint ""
		(layer "F.Cu")
		(at 186.24423 -118.711472 180)
		(property "Reference" "R1247"
			(at -1.20777 0.514858 0)
			(unlocked yes)
			(layer "F.SilkS")
			(effects
				(font
					(size 0.7874 0.5842)
					(thickness 0.1524)
				)
				(justify left)
			)
		)
		(property "Value" ""
			(at 0 0 180)
			(layer "F.Fab")
			(effects
				(font
					(size 1.27 1.27)
				)
			)
		)
		(duplicate_pad_numbers_are_jumpers no)
		(fp_line
			(start 0.7874 0.4064)
			(end -0.7874 0.4064)
			(stroke
				(width 0.1524)
				(type default)
			)
			(layer "F.SilkS")
		)
		(fp_line
			(start 0.7874 -0.4064)
			(end 0.7874 0.4064)
			(stroke
				(width 0.1524)
				(type default)
			)
			(layer "F.SilkS")
		)
		(fp_line
			(start -0.7874 0.4064)
			(end -0.7874 -0.4064)
			(stroke
				(width 0.1524)
				(type default)
			)
			(layer "F.SilkS")
		)
		(fp_line
			(start -0.7874 -0.4064)
			(end 0.7874 -0.4064)
			(stroke
				(width 0.1524)
				(type default)
			)
			(layer "F.SilkS")
		)
		(fp_poly
			(pts
				(xy -0.508 0.2794) (xy -0.508 0.2286) (xy -0.635 0.2286) (xy -0.635 -0.254) (xy -0.5334 -0.254)
				(xy -0.5334 -0.2794) (xy 0.5334 -0.2794) (xy 0.5334 -0.254) (xy 0.635 -0.254) (xy 0.635 0.254) (xy 0.5334 0.254)
				(xy 0.5334 0.2794)
			)
			(stroke
				(width 0)
				(type default)
			)
			(fill no)
			(layer "F.CrtYd")
		)
		(pad "1" smd rect
			(at 0.40005 0 180)
			(size 0.4572 0.508)
			(layers "F.Cu" "F.Mask" "F.Paste")
			(net "PWRGD_NODE1_P3V3_STB_PG_CPLD")
		)
		(pad "2" smd rect
			(at -0.40005 0 180)
			(size 0.4572 0.508)
			(layers "F.Cu" "F.Mask" "F.Paste")
			(net "PWRGD_NODE1_P3V3_STB_PG")
		)
	)
)
